(kicad_pcb
	(version 20260206)
	(generator "pcbnew")
	(generator_version "10.0")
	(general
		(thickness 1.6)
		(legacy_teardrops no)
	)
	(paper "A4")
	(title_block
		(title "Wiwynn_Tioga_Pass_MB.brd")
		(comment 1 "Tioga Pass / footprint 190 of 4770 (U2D1), pads 2735-2823 of 3647")
	)
	(layers
		(0 "F.Cu" signal "TOP")
		(4 "In1.Cu" signal "L2GND")
		(6 "In2.Cu" signal "L3")
		(8 "In3.Cu" signal "L4GND")
		(10 "In4.Cu" signal "L5")
		(12 "In5.Cu" signal "L6GND")
		(14 "In6.Cu" signal "L7VCC")
		(16 "In7.Cu" signal "L8VCC")
		(18 "In8.Cu" signal "L9GND")
		(20 "In9.Cu" signal "L10")
		(22 "In10.Cu" signal "L11GND")
		(24 "In11.Cu" signal "L12")
		(26 "In12.Cu" signal "L13GND")
		(2 "B.Cu" signal "BOTTOM")
		(9 "F.Adhes" user "F.Adhesive")
		(11 "B.Adhes" user "B.Adhesive")
		(13 "F.Paste" user "Package Geometry/Pastemask Top")
		(15 "B.Paste" user "Package Geometry/Pastemask Bottom")
		(5 "F.SilkS" user "Ref Des/Silkscreen Top")
		(7 "B.SilkS" user "Ref Des/Silkscreen Bottom")
		(1 "F.Mask" user "Board Geometry/Soldermask Top")
		(3 "B.Mask" user "Board Geometry/Soldermask Bottom")
		(17 "Dwgs.User" user "User.Drawings")
		(19 "Cmts.User" user "User.Comments")
		(21 "Eco1.User" user "User.Eco1")
		(23 "Eco2.User" user "User.Eco2")
		(25 "Edge.Cuts" user "Board Geometry/Outline")
		(27 "Margin" user)
		(31 "F.CrtYd" user "Package Geometry/Place Bound Top")
		(29 "B.CrtYd" user "Package Geometry/Place Bound Bottom")
		(35 "F.Fab" user "Ref Des/Assembly Top")
		(33 "B.Fab" user "Ref Des/Assembly Bottom")
	)
	(footprint ""
		(layer "F.Cu")
		(at 104.99979 -76.550012 180)
		(property "Reference" "U2D1"
			(at 25.19299 30.484318 0)
			(unlocked yes)
			(layer "F.SilkS")
			(effects
				(font
					(size 0.7874 0.5842)
					(thickness 0.1524)
				)
			)
		)
		(property "Value" ""
			(at 0 0 180)
			(layer "F.Fab")
			(effects
				(font
					(size 1.27 1.27)
				)
			)
		)
		(duplicate_pad_numbers_are_jumpers no)
		(pad "DY7" smd circle
			(at -32.099504 23.931626)
			(size 0.4318 0.4318)
			(layers "F.Cu" "F.Mask" "F.Paste")
			(net "TP_P3E_CPU1_PE1_RSR3_TXN<13>")
		)
		(pad "DY9" smd circle
			(at -30.382464 23.931626)
			(size 0.4318 0.4318)
			(layers "F.Cu" "F.Mask" "F.Paste")
			(net "P3E_CPU1_PE3_MP_TXP<4>")
		)
		(pad "DY11" smd circle
			(at -28.665424 23.931626)
			(size 0.4318 0.4318)
			(layers "F.Cu" "F.Mask" "F.Paste")
			(net "P3E_CPU1_PE3_MP_TXN<3>")
		)
		(pad "DY13" smd circle
			(at -26.948384 23.931626)
			(size 0.4318 0.4318)
			(layers "F.Cu" "F.Mask" "F.Paste")
			(net "TP_P3E_CPU1_PE1_RSR3_RXP<13>")
		)
		(pad "DY15" smd circle
			(at -25.231598 23.931626)
			(size 0.4318 0.4318)
			(layers "F.Cu" "F.Mask" "F.Paste")
			(net "TP_P3E_CPU1_PE1_RSR3_RXN<14>")
		)
		(pad "DY17" smd circle
			(at -23.514558 23.931626)
			(size 0.4318 0.4318)
			(layers "F.Cu" "F.Mask" "F.Paste")
			(net "P3E_CPU1_PE3_MP_RXP<0>")
		)
		(pad "DY19" smd circle
			(at -21.797518 23.931626)
			(size 0.4318 0.4318)
			(layers "F.Cu" "F.Mask" "F.Paste")
			(net "GND")
		)
		(pad "DY21" smd circle
			(at -20.080478 23.931626)
			(size 0.4318 0.4318)
			(layers "F.Cu" "F.Mask" "F.Paste")
			(net "M_K_DQ<58>")
		)
		(pad "DY23" smd circle
			(at -18.363438 23.931626)
			(size 0.4318 0.4318)
			(layers "F.Cu" "F.Mask" "F.Paste")
			(net "GND")
		)
		(pad "DY25" smd circle
			(at -16.646398 23.931626)
			(size 0.4318 0.4318)
			(layers "F.Cu" "F.Mask" "F.Paste")
			(net "M_L_DQ<54>")
		)
		(pad "DY27" smd circle
			(at -14.929612 23.931626)
			(size 0.4318 0.4318)
			(layers "F.Cu" "F.Mask" "F.Paste")
			(net "M_L_DQ<52>")
		)
		(pad "DY29" smd circle
			(at -13.212572 23.931626)
			(size 0.4318 0.4318)
			(layers "F.Cu" "F.Mask" "F.Paste")
			(net "GND")
		)
		(pad "DY31" smd circle
			(at -11.495532 23.931626)
			(size 0.4318 0.4318)
			(layers "F.Cu" "F.Mask" "F.Paste")
			(net "M_L_DQ<46>")
		)
		(pad "DY33" smd circle
			(at -9.778492 23.931626)
			(size 0.4318 0.4318)
			(layers "F.Cu" "F.Mask" "F.Paste")
			(net "M_L_DQ<44>")
		)
		(pad "DY35" smd circle
			(at -8.061452 23.931626)
			(size 0.4318 0.4318)
			(layers "F.Cu" "F.Mask" "F.Paste")
			(net "GND")
		)
		(pad "DY37" smd circle
			(at -6.344412 23.931626)
			(size 0.4318 0.4318)
			(layers "F.Cu" "F.Mask" "F.Paste")
			(net "M_K_DQ<38>")
		)
		(pad "DY39" smd circle
			(at -4.627626 23.931626)
			(size 0.4318 0.4318)
			(layers "F.Cu" "F.Mask" "F.Paste")
			(net "M_K_DQ<36>")
		)
		(pad "DY41" smd circle
			(at -2.910586 23.931626)
			(size 0.4318 0.4318)
			(layers "F.Cu" "F.Mask" "F.Paste")
			(net "GND")
		)
		(pad "DY45" smd circle
			(at 2.052066 22.131274)
			(size 0.4318 0.4318)
			(layers "F.Cu" "F.Mask" "F.Paste")
			(net "GND")
		)
		(pad "DY47" smd circle
			(at 3.769106 22.131274)
			(size 0.4318 0.4318)
			(layers "F.Cu" "F.Mask" "F.Paste")
			(net "GND")
		)
		(pad "DY49" smd circle
			(at 5.485892 22.131274)
			(size 0.4318 0.4318)
			(layers "F.Cu" "F.Mask" "F.Paste")
			(net "GND")
		)
		(pad "DY51" smd circle
			(at 7.202932 22.131274)
			(size 0.4318 0.4318)
			(layers "F.Cu" "F.Mask" "F.Paste")
			(net "GND")
		)
		(pad "DY53" smd circle
			(at 8.919972 22.131274)
			(size 0.4318 0.4318)
			(layers "F.Cu" "F.Mask" "F.Paste")
			(net "GND")
		)
		(pad "DY55" smd circle
			(at 10.637012 22.131274)
			(size 0.4318 0.4318)
			(layers "F.Cu" "F.Mask" "F.Paste")
			(net "GND")
		)
		(pad "DY57" smd circle
			(at 12.354052 22.131274)
			(size 0.4318 0.4318)
			(layers "F.Cu" "F.Mask" "F.Paste")
			(net "GND")
		)
		(pad "DY59" smd circle
			(at 14.071092 22.131274)
			(size 0.4318 0.4318)
			(layers "F.Cu" "F.Mask" "F.Paste")
			(net "GND")
		)
		(pad "DY61" smd circle
			(at 15.787878 22.131274)
			(size 0.4318 0.4318)
			(layers "F.Cu" "F.Mask" "F.Paste")
			(net "GND")
		)
		(pad "DY63" smd circle
			(at 17.504918 22.131274)
			(size 0.4318 0.4318)
			(layers "F.Cu" "F.Mask" "F.Paste")
			(net "GND")
		)
		(pad "DY65" smd circle
			(at 19.221958 22.131274)
			(size 0.4318 0.4318)
			(layers "F.Cu" "F.Mask" "F.Paste")
			(net "M_L_ECC<3>")
		)
		(pad "DY67" smd circle
			(at 20.938998 22.131274)
			(size 0.4318 0.4318)
			(layers "F.Cu" "F.Mask" "F.Paste")
			(net "M_L_DQS_DP<8>")
		)
		(pad "DY69" smd circle
			(at 22.656038 22.131274)
			(size 0.4318 0.4318)
			(layers "F.Cu" "F.Mask" "F.Paste")
			(net "M_L_ECC<0>")
		)
		(pad "DY71" smd circle
			(at 24.373078 22.131274)
			(size 0.4318 0.4318)
			(layers "F.Cu" "F.Mask" "F.Paste")
			(net "GND")
		)
		(pad "DY73" smd circle
			(at 26.090118 22.131274)
			(size 0.4318 0.4318)
			(layers "F.Cu" "F.Mask" "F.Paste")
			(net "M_L_DQS_DP<12>")
		)
		(pad "DY75" smd circle
			(at 27.806904 22.131274)
			(size 0.4318 0.4318)
			(layers "F.Cu" "F.Mask" "F.Paste")
			(net "GND")
		)
		(pad "DY77" smd circle
			(at 29.523944 22.131274)
			(size 0.4318 0.4318)
			(layers "F.Cu" "F.Mask" "F.Paste")
			(net "M_L_DQ<18>")
		)
		(pad "DY79" smd circle
			(at 31.240984 22.131274)
			(size 0.4318 0.4318)
			(layers "F.Cu" "F.Mask" "F.Paste")
			(net "M_L_DQS_DN<11>")
		)
		(pad "DY81" smd circle
			(at 32.958024 22.131274)
			(size 0.4318 0.4318)
			(layers "F.Cu" "F.Mask" "F.Paste")
			(net "M_L_DQ<20>")
		)
		(pad "DY83" smd circle
			(at 34.675064 22.131274)
			(size 0.4318 0.4318)
			(layers "F.Cu" "F.Mask" "F.Paste")
			(net "M_K_DQ<11>")
		)
		(pad "DY85" smd custom
			(at 36.392104 22.131274 225)
			(size 0.10795 0.10795)
			(layers "F.Cu" "F.Mask" "F.Paste")
			(net "GND")
			(options
				(clearance outline)
				(anchor circle)
			)
			(primitives
				(gr_poly
					(pts
						(arc
							(start 0.2159 -0.0381)
							(mid 0 -0.254)
							(end -0.2159 -0.0381)
						)
						(arc
							(start -0.2159 0.0381)
							(mid 0 0.254)
							(end 0.2159 0.0381)
						)
					)
					(width 0)
					(fill yes)
				)
			)
		)
		(pad "E2" smd custom
			(at -36.392104 -23.122128 45)
			(size 0.10795 0.10795)
			(layers "F.Cu" "F.Mask" "F.Paste")
			(net "TP_CPU1_RSVD_283")
			(options
				(clearance outline)
				(anchor circle)
			)
			(primitives
				(gr_poly
					(pts
						(arc
							(start 0.2159 -0.0381)
							(mid 0 -0.254)
							(end -0.2159 -0.0381)
						)
						(arc
							(start -0.2159 0.0381)
							(mid 0 0.254)
							(end 0.2159 0.0381)
						)
					)
					(width 0)
					(fill yes)
				)
			)
		)
		(pad "E4" smd custom
			(at -34.675064 -23.122128 45)
			(size 0.10795 0.10795)
			(layers "F.Cu" "F.Mask" "F.Paste")
			(net "TP_CPU1_RSVD_282")
			(options
				(clearance outline)
				(anchor circle)
			)
			(primitives
				(gr_poly
					(pts
						(arc
							(start 0.2159 -0.0381)
							(mid 0 -0.254)
							(end -0.2159 -0.0381)
						)
						(arc
							(start -0.2159 0.0381)
							(mid 0 0.254)
							(end 0.2159 0.0381)
						)
					)
					(width 0)
					(fill yes)
				)
			)
		)
		(pad "E6" smd circle
			(at -32.958024 -23.122128)
			(size 0.4318 0.4318)
			(layers "F.Cu" "F.Mask" "F.Paste")
			(net "GND")
		)
		(pad "E8" smd circle
			(at -31.240984 -23.122128)
			(size 0.4318 0.4318)
			(layers "F.Cu" "F.Mask" "F.Paste")
			(net "GND")
		)
		(pad "E10" smd circle
			(at -29.523944 -23.122128)
			(size 0.4318 0.4318)
			(layers "F.Cu" "F.Mask" "F.Paste")
			(net "UPI_CPU1_CPU0_P1P1_DN<8>")
		)
		(pad "E12" smd circle
			(at -27.806904 -23.122128)
			(size 0.4318 0.4318)
			(layers "F.Cu" "F.Mask" "F.Paste")
			(net "UPI_CPU1_CPU0_P1P1_DN<10>")
		)
		(pad "E14" smd circle
			(at -26.090118 -23.122128)
			(size 0.4318 0.4318)
			(layers "F.Cu" "F.Mask" "F.Paste")
			(net "UPI_CPU1_CPU0_P1P1_DP<12>")
		)
		(pad "E16" smd circle
			(at -24.373078 -23.122128)
			(size 0.4318 0.4318)
			(layers "F.Cu" "F.Mask" "F.Paste")
			(net "GND")
		)
		(pad "E18" smd custom
			(at -22.656038 -23.122128)
			(size 0.10795 0.10795)
			(layers "F.Cu" "F.Mask" "F.Paste")
			(net "GND")
			(options
				(clearance outline)
				(anchor circle)
			)
			(primitives
				(gr_poly
					(pts
						(arc
							(start 0.2159 -0.0381)
							(mid 0 -0.254)
							(end -0.2159 -0.0381)
						)
						(arc
							(start -0.2159 0.0381)
							(mid 0 0.254)
							(end 0.2159 0.0381)
						)
					)
					(width 0)
					(fill yes)
				)
			)
		)
		(pad "E20" smd custom
			(at -20.938998 -23.122128)
			(size 0.10795 0.10795)
			(layers "F.Cu" "F.Mask" "F.Paste")
			(net "GND")
			(options
				(clearance outline)
				(anchor circle)
			)
			(primitives
				(gr_poly
					(pts
						(arc
							(start 0.2159 -0.0381)
							(mid 0 -0.254)
							(end -0.2159 -0.0381)
						)
						(arc
							(start -0.2159 0.0381)
							(mid 0 0.254)
							(end 0.2159 0.0381)
						)
					)
					(width 0)
					(fill yes)
				)
			)
		)
		(pad "E22" smd custom
			(at -19.221958 -23.122128)
			(size 0.10795 0.10795)
			(layers "F.Cu" "F.Mask" "F.Paste")
			(net "GND")
			(options
				(clearance outline)
				(anchor circle)
			)
			(primitives
				(gr_poly
					(pts
						(arc
							(start 0.2159 -0.0381)
							(mid 0 -0.254)
							(end -0.2159 -0.0381)
						)
						(arc
							(start -0.2159 0.0381)
							(mid 0 0.254)
							(end 0.2159 0.0381)
						)
					)
					(width 0)
					(fill yes)
				)
			)
		)
		(pad "E24" smd custom
			(at -17.504918 -23.122128)
			(size 0.10795 0.10795)
			(layers "F.Cu" "F.Mask" "F.Paste")
			(net "TP_CPU1_RSVD_281")
			(options
				(clearance outline)
				(anchor circle)
			)
			(primitives
				(gr_poly
					(pts
						(arc
							(start 0.2159 -0.0381)
							(mid 0 -0.254)
							(end -0.2159 -0.0381)
						)
						(arc
							(start -0.2159 0.0381)
							(mid 0 0.254)
							(end 0.2159 0.0381)
						)
					)
					(width 0)
					(fill yes)
				)
			)
		)
		(pad "E26" smd circle
			(at -15.787878 -23.122128)
			(size 0.4318 0.4318)
			(layers "F.Cu" "F.Mask" "F.Paste")
			(net "M_H_DQ<51>")
		)
		(pad "E28" smd circle
			(at -14.071092 -23.122128)
			(size 0.4318 0.4318)
			(layers "F.Cu" "F.Mask" "F.Paste")
			(net "M_H_DQS_DP<6>")
		)
		(pad "E30" smd circle
			(at -12.354052 -23.122128)
			(size 0.4318 0.4318)
			(layers "F.Cu" "F.Mask" "F.Paste")
			(net "M_H_DQ<52>")
		)
		(pad "E32" smd circle
			(at -10.637012 -23.122128)
			(size 0.4318 0.4318)
			(layers "F.Cu" "F.Mask" "F.Paste")
			(net "M_H_DQ<43>")
		)
		(pad "E34" smd circle
			(at -8.919972 -23.122128)
			(size 0.4318 0.4318)
			(layers "F.Cu" "F.Mask" "F.Paste")
			(net "M_H_DQS_DP<5>")
		)
		(pad "E36" smd circle
			(at -7.202932 -23.122128)
			(size 0.4318 0.4318)
			(layers "F.Cu" "F.Mask" "F.Paste")
			(net "M_H_DQ<44>")
		)
		(pad "E38" smd circle
			(at -5.485892 -23.122128)
			(size 0.4318 0.4318)
			(layers "F.Cu" "F.Mask" "F.Paste")
			(net "M_G_DQ<35>")
		)
		(pad "E40" smd circle
			(at -3.769106 -23.122128)
			(size 0.4318 0.4318)
			(layers "F.Cu" "F.Mask" "F.Paste")
			(net "M_G_DQS_DP<4>")
		)
		(pad "E42" smd circle
			(at -2.052066 -23.122128)
			(size 0.4318 0.4318)
			(layers "F.Cu" "F.Mask" "F.Paste")
			(net "M_G_DQ<36>")
		)
		(pad "E46" smd circle
			(at 2.910586 -24.921972)
			(size 0.4318 0.4318)
			(layers "F.Cu" "F.Mask" "F.Paste")
			(net "PVDDQ_GHJ")
		)
		(pad "E48" smd circle
			(at 4.627626 -24.921972)
			(size 0.4318 0.4318)
			(layers "F.Cu" "F.Mask" "F.Paste")
			(net "PVDDQ_GHJ")
		)
		(pad "E50" smd circle
			(at 6.344412 -24.921972)
			(size 0.4318 0.4318)
			(layers "F.Cu" "F.Mask" "F.Paste")
			(net "PVDDQ_GHJ")
		)
		(pad "E52" smd circle
			(at 8.061452 -24.921972)
			(size 0.4318 0.4318)
			(layers "F.Cu" "F.Mask" "F.Paste")
			(net "PVDDQ_GHJ")
		)
		(pad "E54" smd circle
			(at 9.778492 -24.921972)
			(size 0.4318 0.4318)
			(layers "F.Cu" "F.Mask" "F.Paste")
			(net "PVDDQ_GHJ")
		)
		(pad "E56" smd circle
			(at 11.495532 -24.921972)
			(size 0.4318 0.4318)
			(layers "F.Cu" "F.Mask" "F.Paste")
			(net "PVDDQ_GHJ")
		)
		(pad "E58" smd circle
			(at 13.212572 -24.921972)
			(size 0.4318 0.4318)
			(layers "F.Cu" "F.Mask" "F.Paste")
			(net "PVDDQ_GHJ")
		)
		(pad "E60" smd circle
			(at 14.929612 -24.921972)
			(size 0.4318 0.4318)
			(layers "F.Cu" "F.Mask" "F.Paste")
			(net "PVDDQ_GHJ")
		)
		(pad "E62" smd circle
			(at 16.646398 -24.921972)
			(size 0.4318 0.4318)
			(layers "F.Cu" "F.Mask" "F.Paste")
			(net "PVDDQ_GHJ")
		)
		(pad "E64" smd circle
			(at 18.363438 -24.921972)
			(size 0.4318 0.4318)
			(layers "F.Cu" "F.Mask" "F.Paste")
			(net "PVDDQ_GHJ")
		)
		(pad "E66" smd custom
			(at 20.080478 -24.921972)
			(size 0.10795 0.10795)
			(layers "F.Cu" "F.Mask" "F.Paste")
			(net "GND")
			(options
				(clearance outline)
				(anchor circle)
			)
			(primitives
				(gr_poly
					(pts
						(arc
							(start 0.2159 -0.0381)
							(mid 0 -0.254)
							(end -0.2159 -0.0381)
						)
						(arc
							(start -0.2159 0.0381)
							(mid 0 0.254)
							(end 0.2159 0.0381)
						)
					)
					(width 0)
					(fill yes)
				)
			)
		)
		(pad "E72" smd circle
			(at 25.231598 -24.921972)
			(size 0.4318 0.4318)
			(layers "F.Cu" "F.Mask" "F.Paste")
			(net "GND")
		)
		(pad "E74" smd circle
			(at 26.948384 -24.921972)
			(size 0.4318 0.4318)
			(layers "F.Cu" "F.Mask" "F.Paste")
			(net "GND")
		)
		(pad "E76" smd circle
			(at 28.665424 -24.921972)
			(size 0.4318 0.4318)
			(layers "F.Cu" "F.Mask" "F.Paste")
			(net "GND")
		)
		(pad "E78" smd circle
			(at 30.382464 -24.921972)
			(size 0.4318 0.4318)
			(layers "F.Cu" "F.Mask" "F.Paste")
			(net "M_H_DQ<22>")
		)
		(pad "E80" smd circle
			(at 32.099504 -24.921972)
			(size 0.4318 0.4318)
			(layers "F.Cu" "F.Mask" "F.Paste")
			(net "M_H_DQ<16>")
		)
		(pad "E82" smd custom
			(at 33.816544 -24.921972 315)
			(size 0.10795 0.10795)
			(layers "F.Cu" "F.Mask" "F.Paste")
			(net "GND")
			(options
				(clearance outline)
				(anchor circle)
			)
			(primitives
				(gr_poly
					(pts
						(arc
							(start 0.2159 -0.0381)
							(mid 0 -0.254)
							(end -0.2159 -0.0381)
						)
						(arc
							(start -0.2159 0.0381)
							(mid 0 0.254)
							(end 0.2159 0.0381)
						)
					)
					(width 0)
					(fill yes)
				)
			)
		)
		(pad "E84" smd custom
			(at 35.533584 -24.921972 270)
			(size 0.10795 0.10795)
			(layers "F.Cu" "F.Mask" "F.Paste")
			(net "TP_CPU1_RSVD_280")
			(options
				(clearance outline)
				(anchor circle)
			)
			(primitives
				(gr_poly
					(pts
						(arc
							(start 0.2159 -0.0381)
							(mid 0 -0.254)
							(end -0.2159 -0.0381)
						)
						(arc
							(start -0.2159 0.0381)
							(mid 0 0.254)
							(end 0.2159 0.0381)
						)
					)
					(width 0)
					(fill yes)
				)
			)
		)
		(pad "EA4" smd custom
			(at -34.675064 24.426672 135)
			(size 0.10795 0.10795)
			(layers "F.Cu" "F.Mask" "F.Paste")
			(net "TP_CPU1_RSVD_20")
			(options
				(clearance outline)
				(anchor circle)
			)
			(primitives
				(gr_poly
					(pts
						(arc
							(start 0.2159 -0.0381)
							(mid 0 -0.254)
							(end -0.2159 -0.0381)
						)
						(arc
							(start -0.2159 0.0381)
							(mid 0 0.254)
							(end 0.2159 0.0381)
						)
					)
					(width 0)
					(fill yes)
				)
			)
		)
		(pad "EA6" smd circle
			(at -32.958024 24.426672)
			(size 0.4318 0.4318)
			(layers "F.Cu" "F.Mask" "F.Paste")
			(net "GND")
		)
		(pad "EA8" smd circle
			(at -31.240984 24.426672)
			(size 0.4318 0.4318)
			(layers "F.Cu" "F.Mask" "F.Paste")
			(net "TP_P3E_CPU1_PE1_RSR3_TXN<14>")
		)
		(pad "EA10" smd circle
			(at -29.523944 24.426672)
			(size 0.4318 0.4318)
			(layers "F.Cu" "F.Mask" "F.Paste")
			(net "P3E_CPU1_PE3_MP_TXP<3>")
		)
		(pad "EA12" smd circle
			(at -27.806904 24.426672)
			(size 0.4318 0.4318)
			(layers "F.Cu" "F.Mask" "F.Paste")
			(net "PVCCIO_CPU1")
		)
		(pad "EA14" smd circle
			(at -26.090118 24.426672)
			(size 0.4318 0.4318)
			(layers "F.Cu" "F.Mask" "F.Paste")
			(net "GND")
		)
		(pad "EA16" smd custom
			(at -24.373078 24.426672 180)
			(size 0.10795 0.10795)
			(layers "F.Cu" "F.Mask" "F.Paste")
			(net "GND")
			(options
				(clearance outline)
				(anchor circle)
			)
			(primitives
				(gr_poly
					(pts
						(arc
							(start 0.2159 -0.0381)
							(mid 0 -0.254)
							(end -0.2159 -0.0381)
						)
						(arc
							(start -0.2159 0.0381)
							(mid 0 0.254)
							(end 0.2159 0.0381)
						)
					)
					(width 0)
					(fill yes)
				)
			)
		)
		(pad "EA18" smd custom
			(at -22.656038 24.426672 180)
			(size 0.10795 0.10795)
			(layers "F.Cu" "F.Mask" "F.Paste")
			(net "P3E_CPU1_PE3_MP_RXN<0>")
			(options
				(clearance outline)
				(anchor circle)
			)
			(primitives
				(gr_poly
					(pts
						(arc
							(start 0.2159 -0.0381)
							(mid 0 -0.254)
							(end -0.2159 -0.0381)
						)
						(arc
							(start -0.2159 0.0381)
							(mid 0 0.254)
							(end 0.2159 0.0381)
						)
					)
					(width 0)
					(fill yes)
				)
			)
		)
		(pad "EA20" smd custom
			(at -20.938998 24.426672 120)
			(size 0.10795 0.10795)
			(layers "F.Cu" "F.Mask" "F.Paste")
			(net "GND")
			(options
				(clearance outline)
				(anchor circle)
			)
			(primitives
				(gr_poly
					(pts
						(arc
							(start 0.2159 -0.0381)
							(mid 0 -0.254)
							(end -0.2159 -0.0381)
						)
						(arc
							(start -0.2159 0.0381)
							(mid 0 0.254)
							(end 0.2159 0.0381)
						)
					)
					(width 0)
					(fill yes)
				)
			)
		)
		(pad "EA22" smd circle
			(at -19.221958 24.426672)
			(size 0.4318 0.4318)
			(layers "F.Cu" "F.Mask" "F.Paste")
			(net "GND")
		)
		(pad "EA24" smd circle
			(at -17.504918 24.426672)
			(size 0.4318 0.4318)
			(layers "F.Cu" "F.Mask" "F.Paste")
			(net "M_L_DQ<50>")
		)
	)
)
